# T6G (Grand Teton) — schematic netlist excerpt (pin names and nets, part order shuffled) for the footprints in the layout excerpt that follows; sources: Cadence DE-HDL packaged netlist, KiCad conversion of 04192023_DAF0TMB3IC0_F0TG_MB_C_brd_V02_OCP.brd

R5021  Q_RES  1K 1% EMPTY  pkg 0402LF  page 159 : A = PVDD11_S3_P1 ; B = I3C_SCM_3_R_SDA
PC111_6  Q_CAP  0.1UF 25V 10% X7R  pkg 0402  page 203 : A = PVDDCR_CPU1_P0_VCCS ; B = GND

(kicad_pcb
	(version 20260206)
	(generator "pcbnew")
	(generator_version "10.0")
	(general
		(thickness 1.6)
		(legacy_teardrops no)
	)
	(paper "A4")
	(title_block
		(title "04192023_DAF0TMB3IC0_F0TG_MB_C_brd_V02_OCP.brd")
		(comment 1 "Grand Teton / footprints 3460-3461 of 8354")
	)
	(layers
		(0 "F.Cu" signal "TOP")
		(4 "In1.Cu" signal "GND")
		(6 "In2.Cu" signal "IN1")
		(8 "In3.Cu" signal "GND1")
		(10 "In4.Cu" signal "IN2")
		(12 "In5.Cu" signal "GND2")
		(14 "In6.Cu" signal "IN3")
		(16 "In7.Cu" signal "GND3")
		(18 "In8.Cu" signal "VCC")
		(20 "In9.Cu" signal "VCC1")
		(22 "In10.Cu" signal "GND4")
		(24 "In11.Cu" signal "IN4")
		(26 "In12.Cu" signal "GND5")
		(28 "In13.Cu" signal "IN5")
		(30 "In14.Cu" signal "GND6")
		(32 "In15.Cu" signal "IN6")
		(34 "In16.Cu" signal "GND7")
		(2 "B.Cu" signal "BOTTOM")
		(9 "F.Adhes" user "F.Adhesive")
		(11 "B.Adhes" user "B.Adhesive")
		(13 "F.Paste" user "Package Geometry/Pastemask Top")
		(15 "B.Paste" user "Package Geometry/Pastemask Bottom")
		(5 "F.SilkS" user "Ref Des/Silkscreen Top")
		(7 "B.SilkS" user "Ref Des/Silkscreen Bottom")
		(1 "F.Mask" user "Board Geometry/Soldermask Top")
		(3 "B.Mask" user "Board Geometry/Soldermask Bottom")
		(17 "Dwgs.User" user "User.Drawings")
		(19 "Cmts.User" user "User.Comments")
		(21 "Eco1.User" user "User.Eco1")
		(23 "Eco2.User" user "User.Eco2")
		(25 "Edge.Cuts" user "Board Geometry/Outline")
		(27 "Margin" user)
		(31 "F.CrtYd" user "Package Geometry/Place Bound Top")
		(29 "B.CrtYd" user "Package Geometry/Place Bound Bottom")
		(35 "F.Fab" user "Ref Des/Assembly Top")
		(33 "B.Fab" user "Ref Des/Assembly Bottom")
	)
	(footprint ""
		(layer "F.Cu")
		(at 183.079898 -160.612074 90)
		(property "Reference" "R5021"
			(at 0 0 90)
			(layer "F.SilkS")
			(hide yes)
			(effects
				(font
					(size 1.27 1.27)
				)
			)
		)
		(property "Value" ""
			(at 0 0 90)
			(layer "F.Fab")
			(effects
				(font
					(size 1.27 1.27)
				)
			)
		)
		(duplicate_pad_numbers_are_jumpers no)
		(fp_line
			(start 0.7874 -0.4064)
			(end 0.7874 0.4064)
			(stroke
				(width 0.1524)
				(type default)
			)
			(layer "F.SilkS")
		)
		(fp_line
			(start -0.7874 -0.4064)
			(end 0.7874 -0.4064)
			(stroke
				(width 0.1524)
				(type default)
			)
			(layer "F.SilkS")
		)
		(fp_line
			(start 0.7874 0.4064)
			(end -0.7874 0.4064)
			(stroke
				(width 0.1524)
				(type default)
			)
			(layer "F.SilkS")
		)
		(fp_line
			(start -0.7874 0.4064)
			(end -0.7874 -0.4064)
			(stroke
				(width 0.1524)
				(type default)
			)
			(layer "F.SilkS")
		)
		(fp_line
			(start -0.12065 -0.305054)
			(end -0.12065 -0.2794)
			(stroke
				(width 0.1)
				(type default)
			)
			(layer "F.Fab")
		)
		(fp_line
			(start -0.67945 -0.305054)
			(end -0.12065 -0.305054)
			(stroke
				(width 0.1)
				(type default)
			)
			(layer "F.Fab")
		)
		(fp_line
			(start 0.67945 -0.3048)
			(end 0.67945 0.3048)
			(stroke
				(width 0.1)
				(type default)
			)
			(layer "F.Fab")
		)
		(fp_line
			(start 0.12065 -0.3048)
			(end 0.67945 -0.3048)
			(stroke
				(width 0.1)
				(type default)
			)
			(layer "F.Fab")
		)
		(fp_line
			(start 0.12065 -0.2794)
			(end 0.12065 -0.3048)
			(stroke
				(width 0.1)
				(type default)
			)
			(layer "F.Fab")
		)
		(fp_line
			(start -0.12065 -0.2794)
			(end 0.12065 -0.2794)
			(stroke
				(width 0.1)
				(type default)
			)
			(layer "F.Fab")
		)
		(fp_line
			(start 0.120396 0.2794)
			(end -0.12065 0.2794)
			(stroke
				(width 0.1)
				(type default)
			)
			(layer "F.Fab")
		)
		(fp_line
			(start -0.12065 0.2794)
			(end -0.12065 0.3048)
			(stroke
				(width 0.1)
				(type default)
			)
			(layer "F.Fab")
		)
		(fp_line
			(start 0.67945 0.3048)
			(end 0.120396 0.3048)
			(stroke
				(width 0.1)
				(type default)
			)
			(layer "F.Fab")
		)
		(fp_line
			(start 0.120396 0.3048)
			(end 0.120396 0.2794)
			(stroke
				(width 0.1)
				(type default)
			)
			(layer "F.Fab")
		)
		(fp_line
			(start -0.12065 0.3048)
			(end -0.67945 0.3048)
			(stroke
				(width 0.1)
				(type default)
			)
			(layer "F.Fab")
		)
		(fp_line
			(start -0.67945 0.3048)
			(end -0.67945 -0.305054)
			(stroke
				(width 0.1)
				(type default)
			)
			(layer "F.Fab")
		)
		(pad "1" smd circle
			(at -0.40005 0 90)
			(size 0 0)
			(layers "F.Cu" "F.Mask" "F.Paste")
			(net "PVDD11_S3_P1")
		)
		(pad "2" smd circle
			(at 0.40005 0 90)
			(size 0 0)
			(layers "F.Cu" "F.Mask" "F.Paste")
			(net "I3C_SCM_3_R_SDA")
		)
	)
	(footprint ""
		(layer "F.Cu")
		(at 348.972124 -344.792046 90)
		(property "Reference" "PC111_6"
			(at 0 0 90)
			(layer "F.SilkS")
			(hide yes)
			(effects
				(font
					(size 1.27 1.27)
				)
			)
		)
		(property "Value" ""
			(at 0 0 90)
			(layer "F.Fab")
			(effects
				(font
					(size 1.27 1.27)
				)
			)
		)
		(duplicate_pad_numbers_are_jumpers no)
		(fp_line
			(start 0.7874 -0.4064)
			(end 0.7874 0.4064)
			(stroke
				(width 0.1524)
				(type default)
			)
			(layer "F.SilkS")
		)
		(fp_line
			(start -0.7874 -0.4064)
			(end 0.7874 -0.4064)
			(stroke
				(width 0.1524)
				(type default)
			)
			(layer "F.SilkS")
		)
		(fp_line
			(start 0.7874 0.4064)
			(end -0.7874 0.4064)
			(stroke
				(width 0.1524)
				(type default)
			)
			(layer "F.SilkS")
		)
		(fp_line
			(start -0.7874 0.4064)
			(end -0.7874 -0.4064)
			(stroke
				(width 0.1524)
				(type default)
			)
			(layer "F.SilkS")
		)
		(fp_line
			(start -0.12065 -0.305054)
			(end -0.12065 -0.2794)
			(stroke
				(width 0.1)
				(type default)
			)
			(layer "F.Fab")
		)
		(fp_line
			(start -0.67945 -0.305054)
			(end -0.12065 -0.305054)
			(stroke
				(width 0.1)
				(type default)
			)
			(layer "F.Fab")
		)
		(fp_line
			(start 0.67945 -0.3048)
			(end 0.67945 0.3048)
			(stroke
				(width 0.1)
				(type default)
			)
			(layer "F.Fab")
		)
		(fp_line
			(start 0.12065 -0.3048)
			(end 0.67945 -0.3048)
			(stroke
				(width 0.1)
				(type default)
			)
			(layer "F.Fab")
		)
		(fp_line
			(start 0.12065 -0.2794)
			(end 0.12065 -0.3048)
			(stroke
				(width 0.1)
				(type default)
			)
			(layer "F.Fab")
		)
		(fp_line
			(start -0.12065 -0.2794)
			(end 0.12065 -0.2794)
			(stroke
				(width 0.1)
				(type default)
			)
			(layer "F.Fab")
		)
		(fp_line
			(start 0.120396 0.2794)
			(end -0.12065 0.2794)
			(stroke
				(width 0.1)
				(type default)
			)
			(layer "F.Fab")
		)
		(fp_line
			(start -0.12065 0.2794)
			(end -0.12065 0.3048)
			(stroke
				(width 0.1)
				(type default)
			)
			(layer "F.Fab")
		)
		(fp_line
			(start 0.67945 0.3048)
			(end 0.120396 0.3048)
			(stroke
				(width 0.1)
				(type default)
			)
			(layer "F.Fab")
		)
		(fp_line
			(start 0.120396 0.3048)
			(end 0.120396 0.2794)
			(stroke
				(width 0.1)
				(type default)
			)
			(layer "F.Fab")
		)
		(fp_line
			(start -0.12065 0.3048)
			(end -0.67945 0.3048)
			(stroke
				(width 0.1)
				(type default)
			)
			(layer "F.Fab")
		)
		(fp_line
			(start -0.67945 0.3048)
			(end -0.67945 -0.305054)
			(stroke
				(width 0.1)
				(type default)
			)
			(layer "F.Fab")
		)
		(pad "1" smd circle
			(at -0.40005 0 90)
			(size 0 0)
			(layers "F.Cu" "F.Mask" "F.Paste")
			(net "PVDDCR_CPU1_P0_VCCS")
		)
		(pad "2" smd circle
			(at 0.40005 0 90)
			(size 0 0)
			(layers "F.Cu" "F.Mask" "F.Paste")
			(net "GND")
		)
	)
)
